(kicad_pcb
	(version 20260206)
	(generator "pcbnew")
	(generator_version "10.0")
	(general
		(thickness 1.6)
		(legacy_teardrops no)
	)
	(paper "A4")
	(title_block
		(title "Bryce Canyon_R.DPB_16317-1_OCP.brd")
		(comment 1 "Bryce Canyon / footprints 1977-1982 of 2099")
	)
	(layers
		(0 "F.Cu" signal "TOP")
		(4 "In1.Cu" signal "L2GND")
		(6 "In2.Cu" signal "L3")
		(8 "In3.Cu" signal "L4VCC")
		(10 "In4.Cu" signal "L5VCC")
		(12 "In5.Cu" signal "L6")
		(14 "In6.Cu" signal "L7GND")
		(2 "B.Cu" signal "BOTTOM")
		(9 "F.Adhes" user "F.Adhesive")
		(11 "B.Adhes" user "B.Adhesive")
		(13 "F.Paste" user "Package Geometry/Pastemask Top")
		(15 "B.Paste" user "Package Geometry/Pastemask Bottom")
		(5 "F.SilkS" user "Ref Des/Silkscreen Top")
		(7 "B.SilkS" user "Ref Des/Silkscreen Bottom")
		(1 "F.Mask" user "Board Geometry/Soldermask Top")
		(3 "B.Mask" user "Board Geometry/Soldermask Bottom")
		(17 "Dwgs.User" user "User.Drawings")
		(19 "Cmts.User" user "User.Comments")
		(21 "Eco1.User" user "User.Eco1")
		(23 "Eco2.User" user "User.Eco2")
		(25 "Edge.Cuts" user "Board Geometry/Outline")
		(27 "Margin" user)
		(31 "F.CrtYd" user "Package Geometry/Place Bound Top")
		(29 "B.CrtYd" user "Package Geometry/Place Bound Bottom")
		(35 "F.Fab" user "Ref Des/Assembly Top")
		(33 "B.Fab" user "Ref Des/Assembly Bottom")
	)
	(footprint ""
		(layer "B.Cu")
		(at 240.6904 -281.8384 -90)
		(property "Reference" "C703"
			(at 0 0 90)
			(layer "B.SilkS")
			(hide yes)
			(effects
				(font
					(size 1.27 1.27)
				)
				(justify mirror)
			)
		)
		(property "Value" "SC10U6D3V5KX-4GP"
			(at 0.0762 -6.1214 270)
			(unlocked yes)
			(layer "B.Fab")
			(hide yes)
			(effects
				(font
					(size 1.016 1.016)
					(thickness 0.1524)
				)
				(justify mirror)
			)
		)
		(property "Device Type" "C805H58"
			(at 0.0762 -8.1534 270)
			(unlocked yes)
			(layer "B.Fab")
			(hide yes)
			(effects
				(font
					(size 1.016 1.016)
					(thickness 0.1524)
				)
				(justify mirror)
			)
		)
		(duplicate_pad_numbers_are_jumpers no)
		(fp_line
			(start -0.635 0)
			(end 0.635 0)
			(stroke
				(width 0.508)
				(type default)
			)
			(layer "B.SilkS")
		)
		(fp_rect
			(start 0.9652 1.778)
			(end -0.9652 -1.778)
			(stroke
				(width 0)
				(type default)
			)
			(fill no)
			(layer "B.CrtYd")
		)
		(fp_poly
			(pts
				(xy 0.9652 -1.778) (xy -0.9652 -1.778) (xy -0.9652 1.778) (xy 0.9652 1.778)
			)
			(stroke
				(width 0)
				(type default)
			)
			(fill no)
			(layer "B.Fab")
		)
		(pad "1" smd rect
			(at 0 -0.9652 90)
			(size 1.397 1.143)
			(layers "B.Cu" "B.Mask" "B.Paste")
			(net "P3V3_STBY_B")
		)
		(pad "2" smd rect
			(at 0 0.9652 90)
			(size 1.397 1.143)
			(layers "B.Cu" "B.Mask" "B.Paste")
			(net "GND")
		)
	)
	(footprint ""
		(layer "B.Cu")
		(at 251.968 -287.274 -90)
		(property "Reference" "C690"
			(at 0 0 90)
			(layer "B.SilkS")
			(hide yes)
			(effects
				(font
					(size 1.27 1.27)
				)
				(justify mirror)
			)
		)
		(property "Value" "SCD1U16V2KX-3GP"
			(at -1.1811 -2.7051 270)
			(unlocked yes)
			(layer "B.Fab")
			(hide yes)
			(effects
				(font
					(size 1.016 1.016)
					(thickness 0.1524)
				)
				(justify mirror)
			)
		)
		(property "Device Type" "C402H22"
			(at -1.1811 -4.2291 270)
			(unlocked yes)
			(layer "B.Fab")
			(hide yes)
			(effects
				(font
					(size 1.016 1.016)
					(thickness 0.1524)
				)
				(justify mirror)
			)
		)
		(duplicate_pad_numbers_are_jumpers no)
		(fp_rect
			(start 0.4318 0.9525)
			(end -0.4318 -0.9525)
			(stroke
				(width 0)
				(type default)
			)
			(fill no)
			(layer "B.CrtYd")
		)
		(fp_rect
			(start 0.4318 0.9525)
			(end -0.4318 -0.9525)
			(stroke
				(width 0)
				(type default)
			)
			(fill no)
			(layer "B.Fab")
		)
		(pad "1" smd custom
			(at 0 -0.4445 90)
			(size 0.1524 0.1524)
			(layers "B.Cu" "B.Mask" "B.Paste")
			(net "P3V3_STBY_VIN")
			(options
				(clearance outline)
				(anchor circle)
			)
			(primitives
				(gr_poly
					(pts
						(arc
							(start 0.3048 0.2032)
							(mid 0.275042 0.275042)
							(end 0.2032 0.3048)
						)
						(arc
							(start -0.2032 0.3048)
							(mid -0.275042 0.275042)
							(end -0.3048 0.2032)
						)
						(arc
							(start -0.3048 -0.2032)
							(mid -0.275042 -0.275042)
							(end -0.2032 -0.3048)
						)
						(arc
							(start 0.2032 -0.3048)
							(mid 0.275042 -0.275042)
							(end 0.3048 -0.2032)
						)
					)
					(width 0)
					(fill yes)
				)
			)
		)
		(pad "2" smd custom
			(at 0 0.4445 90)
			(size 0.1524 0.1524)
			(layers "B.Cu" "B.Mask" "B.Paste")
			(net "GND")
			(options
				(clearance outline)
				(anchor circle)
			)
			(primitives
				(gr_poly
					(pts
						(arc
							(start 0.3048 0.2032)
							(mid 0.275042 0.275042)
							(end 0.2032 0.3048)
						)
						(arc
							(start -0.2032 0.3048)
							(mid -0.275042 0.275042)
							(end -0.3048 0.2032)
						)
						(arc
							(start -0.3048 -0.2032)
							(mid -0.275042 -0.275042)
							(end -0.2032 -0.3048)
						)
						(arc
							(start 0.2032 -0.3048)
							(mid 0.275042 -0.275042)
							(end 0.3048 -0.2032)
						)
					)
					(width 0)
					(fill yes)
				)
			)
		)
	)
	(footprint ""
		(layer "B.Cu")
		(at 260.600698 -281.888946 90)
		(property "Reference" "R1180"
			(at 0 0 90)
			(layer "B.SilkS")
			(hide yes)
			(effects
				(font
					(size 1.27 1.27)
				)
				(justify mirror)
			)
		)
		(property "Value" "10KR2F-2-GP"
			(at -0.064008 -3.993896 90)
			(unlocked yes)
			(layer "B.Fab")
			(hide yes)
			(effects
				(font
					(size 1.016 1.016)
					(thickness 0.1524)
				)
				(justify mirror)
			)
		)
		(property "Device Type" "R402H16"
			(at -0.064008 -5.517896 90)
			(unlocked yes)
			(layer "B.Fab")
			(hide yes)
			(effects
				(font
					(size 1.016 1.016)
					(thickness 0.1524)
				)
				(justify mirror)
			)
		)
		(duplicate_pad_numbers_are_jumpers no)
		(fp_line
			(start 0.508 -0.9398)
			(end 0.508 0.9398)
			(stroke
				(width 0.1524)
				(type default)
			)
			(layer "B.SilkS")
		)
		(fp_line
			(start -0.508 -0.9398)
			(end 0.508 -0.9398)
			(stroke
				(width 0.1524)
				(type default)
			)
			(layer "B.SilkS")
		)
		(fp_rect
			(start 0.508 0.9398)
			(end -0.508 -0.9398)
			(stroke
				(width 0)
				(type default)
			)
			(fill no)
			(layer "B.CrtYd")
		)
		(fp_rect
			(start 0.508 0.9398)
			(end -0.508 -0.9398)
			(stroke
				(width 0)
				(type default)
			)
			(fill no)
			(layer "B.Fab")
		)
		(pad "1" smd custom
			(at 0 -0.4445 270)
			(size 0.1397 0.1397)
			(layers "B.Cu" "B.Mask" "B.Paste")
			(net "P3V3_STBY_VRG5")
			(options
				(clearance outline)
				(anchor circle)
			)
			(primitives
				(gr_poly
					(pts
						(arc
							(start -0.1778 0.2794)
							(mid -0.249642 0.249642)
							(end -0.2794 0.1778)
						)
						(arc
							(start -0.2794 -0.1778)
							(mid -0.249642 -0.249642)
							(end -0.1778 -0.2794)
						)
						(arc
							(start 0.1778 -0.2794)
							(mid 0.249642 -0.249642)
							(end 0.2794 -0.1778)
						)
						(arc
							(start 0.2794 0.1778)
							(mid 0.249642 0.249642)
							(end 0.1778 0.2794)
						)
					)
					(width 0)
					(fill yes)
				)
			)
		)
		(pad "2" smd custom
			(at 0 0.4445 270)
			(size 0.1397 0.1397)
			(layers "B.Cu" "B.Mask" "B.Paste")
			(net "PWRGD_P3V3_STBY")
			(options
				(clearance outline)
				(anchor circle)
			)
			(primitives
				(gr_poly
					(pts
						(arc
							(start -0.1778 0.2794)
							(mid -0.249642 0.249642)
							(end -0.2794 0.1778)
						)
						(arc
							(start -0.2794 -0.1778)
							(mid -0.249642 -0.249642)
							(end -0.1778 -0.2794)
						)
						(arc
							(start 0.1778 -0.2794)
							(mid 0.249642 -0.249642)
							(end 0.2794 -0.1778)
						)
						(arc
							(start 0.2794 0.1778)
							(mid 0.249642 0.249642)
							(end 0.1778 0.2794)
						)
					)
					(width 0)
					(fill yes)
				)
			)
		)
	)
	(footprint ""
		(layer "B.Cu")
		(at 466.917024 -230.911654 -90)
		(property "Reference" "C665"
			(at 0 0 90)
			(layer "B.SilkS")
			(hide yes)
			(effects
				(font
					(size 1.27 1.27)
				)
				(justify mirror)
			)
		)
		(property "Value" "SC470P50V2KX-3GP"
			(at -1.1811 -2.7051 270)
			(unlocked yes)
			(layer "B.Fab")
			(hide yes)
			(effects
				(font
					(size 1.016 1.016)
					(thickness 0.1524)
				)
				(justify mirror)
			)
		)
		(property "Device Type" "C402H22"
			(at -1.1811 -4.2291 270)
			(unlocked yes)
			(layer "B.Fab")
			(hide yes)
			(effects
				(font
					(size 1.016 1.016)
					(thickness 0.1524)
				)
				(justify mirror)
			)
		)
		(duplicate_pad_numbers_are_jumpers no)
		(fp_rect
			(start 0.4318 0.9525)
			(end -0.4318 -0.9525)
			(stroke
				(width 0)
				(type default)
			)
			(fill no)
			(layer "B.CrtYd")
		)
		(fp_rect
			(start 0.4318 0.9525)
			(end -0.4318 -0.9525)
			(stroke
				(width 0)
				(type default)
			)
			(fill no)
			(layer "B.Fab")
		)
		(pad "1" smd custom
			(at 0 -0.4445 90)
			(size 0.1524 0.1524)
			(layers "B.Cu" "B.Mask" "B.Paste")
			(net "P5V_B_3_LL_R")
			(options
				(clearance outline)
				(anchor circle)
			)
			(primitives
				(gr_poly
					(pts
						(arc
							(start 0.3048 0.2032)
							(mid 0.275042 0.275042)
							(end 0.2032 0.3048)
						)
						(arc
							(start -0.2032 0.3048)
							(mid -0.275042 0.275042)
							(end -0.3048 0.2032)
						)
						(arc
							(start -0.3048 -0.2032)
							(mid -0.275042 -0.275042)
							(end -0.2032 -0.3048)
						)
						(arc
							(start 0.2032 -0.3048)
							(mid 0.275042 -0.275042)
							(end 0.3048 -0.2032)
						)
					)
					(width 0)
					(fill yes)
				)
			)
		)
		(pad "2" smd custom
			(at 0 0.4445 90)
			(size 0.1524 0.1524)
			(layers "B.Cu" "B.Mask" "B.Paste")
			(net "P5V_B_3_VFB")
			(options
				(clearance outline)
				(anchor circle)
			)
			(primitives
				(gr_poly
					(pts
						(arc
							(start 0.3048 0.2032)
							(mid 0.275042 0.275042)
							(end 0.2032 0.3048)
						)
						(arc
							(start -0.2032 0.3048)
							(mid -0.275042 0.275042)
							(end -0.3048 0.2032)
						)
						(arc
							(start -0.3048 -0.2032)
							(mid -0.275042 -0.275042)
							(end -0.2032 -0.3048)
						)
						(arc
							(start 0.2032 -0.3048)
							(mid 0.275042 -0.275042)
							(end 0.3048 -0.2032)
						)
					)
					(width 0)
					(fill yes)
				)
			)
		)
	)
	(footprint ""
		(layer "B.Cu")
		(at 31.9532 -222.0976 90)
		(property "Reference" "L2"
			(at 0 0 90)
			(layer "B.SilkS")
			(hide yes)
			(effects
				(font
					(size 1.27 1.27)
				)
				(justify mirror)
			)
		)
		(property "Value" "IND-1UH-191-GP"
			(at 6.7818 -2.1082 90)
			(unlocked yes)
			(layer "B.Fab")
			(hide yes)
			(effects
				(font
					(size 1.016 1.016)
					(thickness 0.1524)
				)
				(justify mirror)
			)
		)
		(property "Device Type" "L109100-2430-UH119"
			(at 6.7818 -3.6322 90)
			(unlocked yes)
			(layer "B.Fab")
			(hide yes)
			(effects
				(font
					(size 1.016 1.016)
					(thickness 0.1524)
				)
				(justify mirror)
			)
		)
		(duplicate_pad_numbers_are_jumpers no)
		(fp_line
			(start 5.2578 -6.4262)
			(end -5.2578 -6.4262)
			(stroke
				(width 0.1524)
				(type default)
			)
			(layer "B.SilkS")
		)
		(fp_line
			(start -5.2578 -6.4262)
			(end -5.2578 6.4262)
			(stroke
				(width 0.1524)
				(type default)
			)
			(layer "B.SilkS")
		)
		(fp_line
			(start 5.2578 6.4262)
			(end 5.2578 -6.4262)
			(stroke
				(width 0.1524)
				(type default)
			)
			(layer "B.SilkS")
		)
		(fp_line
			(start -5.2578 6.4262)
			(end 5.2578 6.4262)
			(stroke
				(width 0.1524)
				(type default)
			)
			(layer "B.SilkS")
		)
		(fp_rect
			(start 5.0038 5.4229)
			(end -5.0038 -5.4229)
			(stroke
				(width 0)
				(type default)
			)
			(fill no)
			(layer "B.CrtYd")
		)
		(fp_poly
			(pts
				(xy 5.5118 6.5024) (xy 5.5118 -6.5024) (xy -5.5118 -6.5024) (xy -5.5118 -0.8509) (xy -5.0038 -0.8509)
				(xy -5.0038 -5.4229) (xy 5.0038 -5.4229) (xy 5.0038 5.4229) (xy -5.0038 5.4229) (xy -5.0038 -0.8382)
				(xy -5.5118 -0.8382) (xy -5.5118 6.5024)
			)
			(stroke
				(width 0)
				(type default)
			)
			(fill no)
			(layer "B.CrtYd")
		)
		(fp_rect
			(start 5.5118 6.5024)
			(end -5.5118 -6.5024)
			(stroke
				(width 0)
				(type default)
			)
			(fill no)
			(layer "B.Fab")
		)
		(pad "1" smd rect
			(at 0 -4.396994 270)
			(size 3.5052 3.556)
			(layers "B.Cu" "B.Mask" "B.Paste")
			(net "P5V_B_1_LL")
		)
		(pad "2" smd rect
			(at 0 4.396994 270)
			(size 3.5052 3.556)
			(layers "B.Cu" "B.Mask" "B.Paste")
			(net "P5V_B_1")
		)
	)
	(footprint ""
		(layer "B.Cu")
		(at 130.263646 -364.93577 180)
		(property "Reference" "R144"
			(at 0 0 0)
			(layer "B.SilkS")
			(hide yes)
			(effects
				(font
					(size 1.27 1.27)
				)
				(justify mirror)
			)
		)
		(property "Value" "200KR2F-L-GP"
			(at -0.064008 -3.993896 180)
			(unlocked yes)
			(layer "B.Fab")
			(hide yes)
			(effects
				(font
					(size 1.016 1.016)
					(thickness 0.1524)
				)
				(justify mirror)
			)
		)
		(property "Device Type" "R402H16"
			(at -0.064008 -5.517896 180)
			(unlocked yes)
			(layer "B.Fab")
			(hide yes)
			(effects
				(font
					(size 1.016 1.016)
					(thickness 0.1524)
				)
				(justify mirror)
			)
		)
		(duplicate_pad_numbers_are_jumpers no)
		(fp_line
			(start 0.508 -0.9398)
			(end 0.508 0.9398)
			(stroke
				(width 0.1524)
				(type default)
			)
			(layer "B.SilkS")
		)
		(fp_line
			(start -0.508 -0.9398)
			(end 0.508 -0.9398)
			(stroke
				(width 0.1524)
				(type default)
			)
			(layer "B.SilkS")
		)
		(fp_rect
			(start 0.508 0.9398)
			(end -0.508 -0.9398)
			(stroke
				(width 0)
				(type default)
			)
			(fill no)
			(layer "B.CrtYd")
		)
		(fp_rect
			(start 0.508 0.9398)
			(end -0.508 -0.9398)
			(stroke
				(width 0)
				(type default)
			)
			(fill no)
			(layer "B.Fab")
		)
		(pad "1" smd custom
			(at 0 -0.4445)
			(size 0.1397 0.1397)
			(layers "B.Cu" "B.Mask" "B.Paste")
			(net "GATE_FAN1")
			(options
				(clearance outline)
				(anchor circle)
			)
			(primitives
				(gr_poly
					(pts
						(arc
							(start -0.1778 0.2794)
							(mid -0.249642 0.249642)
							(end -0.2794 0.1778)
						)
						(arc
							(start -0.2794 -0.1778)
							(mid -0.249642 -0.249642)
							(end -0.1778 -0.2794)
						)
						(arc
							(start 0.1778 -0.2794)
							(mid 0.249642 -0.249642)
							(end 0.2794 -0.1778)
						)
						(arc
							(start 0.2794 0.1778)
							(mid 0.249642 0.249642)
							(end 0.1778 0.2794)
						)
					)
					(width 0)
					(fill yes)
				)
			)
		)
		(pad "2" smd custom
			(at 0 0.4445)
			(size 0.1397 0.1397)
			(layers "B.Cu" "B.Mask" "B.Paste")
			(net "GATE_FAN1_R")
			(options
				(clearance outline)
				(anchor circle)
			)
			(primitives
				(gr_poly
					(pts
						(arc
							(start -0.1778 0.2794)
							(mid -0.249642 0.249642)
							(end -0.2794 0.1778)
						)
						(arc
							(start -0.2794 -0.1778)
							(mid -0.249642 -0.249642)
							(end -0.1778 -0.2794)
						)
						(arc
							(start 0.1778 -0.2794)
							(mid 0.249642 -0.249642)
							(end 0.2794 -0.1778)
						)
						(arc
							(start 0.2794 0.1778)
							(mid 0.249642 0.249642)
							(end 0.1778 0.2794)
						)
					)
					(width 0)
					(fill yes)
				)
			)
		)
	)
)
